# T6G (Grand Teton) — schematic netlist excerpt (pin names and nets, part order shuffled) for the footprints in the layout excerpt that follows; sources: Cadence DE-HDL packaged netlist, KiCad conversion of 04192023_DAF0TMB3IC0_F0TG_MB_C_brd_V02_OCP.brd

C782  Q_CAP  0.1UF 10V 10% X7S  pkg C0201  page 301 : A = P0V9_CPU0_RT_2D ; B = GND
C372  Q_CAP  10UF 6.3V 20% X6S  pkg C0402  page 345 : A = P1V8_CPU1_RT2_1A ; B = GND
R2423  Q_RES  33.2 1% CHIP  pkg 0402LF  page 150 : A = SMB_PMBUS_3V3AUX_SCL ; B = SMB_PMBUS_3V3AUX_SCL_R0

(kicad_pcb
	(version 20260206)
	(generator "pcbnew")
	(generator_version "10.0")
	(general
		(thickness 1.6)
		(legacy_teardrops no)
	)
	(paper "A4")
	(title_block
		(title "04192023_DAF0TMB3IC0_F0TG_MB_C_brd_V02_OCP.brd")
		(comment 1 "Grand Teton / footprints 5559-5561 of 8354")
	)
	(layers
		(0 "F.Cu" signal "TOP")
		(4 "In1.Cu" signal "GND")
		(6 "In2.Cu" signal "IN1")
		(8 "In3.Cu" signal "GND1")
		(10 "In4.Cu" signal "IN2")
		(12 "In5.Cu" signal "GND2")
		(14 "In6.Cu" signal "IN3")
		(16 "In7.Cu" signal "GND3")
		(18 "In8.Cu" signal "VCC")
		(20 "In9.Cu" signal "VCC1")
		(22 "In10.Cu" signal "GND4")
		(24 "In11.Cu" signal "IN4")
		(26 "In12.Cu" signal "GND5")
		(28 "In13.Cu" signal "IN5")
		(30 "In14.Cu" signal "GND6")
		(32 "In15.Cu" signal "IN6")
		(34 "In16.Cu" signal "GND7")
		(2 "B.Cu" signal "BOTTOM")
		(9 "F.Adhes" user "F.Adhesive")
		(11 "B.Adhes" user "B.Adhesive")
		(13 "F.Paste" user "Package Geometry/Pastemask Top")
		(15 "B.Paste" user "Package Geometry/Pastemask Bottom")
		(5 "F.SilkS" user "Ref Des/Silkscreen Top")
		(7 "B.SilkS" user "Ref Des/Silkscreen Bottom")
		(1 "F.Mask" user "Board Geometry/Soldermask Top")
		(3 "B.Mask" user "Board Geometry/Soldermask Bottom")
		(17 "Dwgs.User" user "User.Drawings")
		(19 "Cmts.User" user "User.Comments")
		(21 "Eco1.User" user "User.Eco1")
		(23 "Eco2.User" user "User.Eco2")
		(25 "Edge.Cuts" user "Board Geometry/Outline")
		(27 "Margin" user)
		(31 "F.CrtYd" user "Package Geometry/Place Bound Top")
		(29 "B.CrtYd" user "Package Geometry/Place Bound Bottom")
		(35 "F.Fab" user "Ref Des/Assembly Top")
		(33 "B.Fab" user "Ref Des/Assembly Bottom")
	)
	(footprint ""
		(layer "B.Cu")
		(at 156.61894 -390.560052 90)
		(property "Reference" "C372"
			(at 0 0 90)
			(layer "B.SilkS")
			(hide yes)
			(effects
				(font
					(size 1.27 1.27)
				)
				(justify mirror)
			)
		)
		(property "Value" ""
			(at 0 0 90)
			(layer "B.Fab")
			(effects
				(font
					(size 1.27 1.27)
				)
				(justify mirror)
			)
		)
		(duplicate_pad_numbers_are_jumpers no)
		(fp_line
			(start 0.7874 -0.4064)
			(end -0.7874 -0.4064)
			(stroke
				(width 0.1524)
				(type default)
			)
			(layer "B.SilkS")
		)
		(fp_line
			(start -0.7874 -0.4064)
			(end -0.7874 0.4064)
			(stroke
				(width 0.1524)
				(type default)
			)
			(layer "B.SilkS")
		)
		(fp_line
			(start 0.7874 0.4064)
			(end 0.7874 -0.4064)
			(stroke
				(width 0.1524)
				(type default)
			)
			(layer "B.SilkS")
		)
		(fp_line
			(start -0.7874 0.4064)
			(end 0.7874 0.4064)
			(stroke
				(width 0.1524)
				(type default)
			)
			(layer "B.SilkS")
		)
		(fp_line
			(start 0.67945 -0.305054)
			(end 0.12065 -0.305054)
			(stroke
				(width 0.1)
				(type default)
			)
			(layer "B.Fab")
		)
		(fp_line
			(start 0.12065 -0.305054)
			(end 0.12065 -0.2794)
			(stroke
				(width 0.1)
				(type default)
			)
			(layer "B.Fab")
		)
		(fp_line
			(start -0.12065 -0.3048)
			(end -0.67945 -0.3048)
			(stroke
				(width 0.1)
				(type default)
			)
			(layer "B.Fab")
		)
		(fp_line
			(start -0.67945 -0.3048)
			(end -0.67945 0.3048)
			(stroke
				(width 0.1)
				(type default)
			)
			(layer "B.Fab")
		)
		(fp_line
			(start 0.12065 -0.2794)
			(end -0.12065 -0.2794)
			(stroke
				(width 0.1)
				(type default)
			)
			(layer "B.Fab")
		)
		(fp_line
			(start -0.12065 -0.2794)
			(end -0.12065 -0.3048)
			(stroke
				(width 0.1)
				(type default)
			)
			(layer "B.Fab")
		)
		(fp_line
			(start 0.12065 0.2794)
			(end 0.12065 0.3048)
			(stroke
				(width 0.1)
				(type default)
			)
			(layer "B.Fab")
		)
		(fp_line
			(start -0.120396 0.2794)
			(end 0.12065 0.2794)
			(stroke
				(width 0.1)
				(type default)
			)
			(layer "B.Fab")
		)
		(fp_line
			(start 0.67945 0.3048)
			(end 0.67945 -0.305054)
			(stroke
				(width 0.1)
				(type default)
			)
			(layer "B.Fab")
		)
		(fp_line
			(start 0.12065 0.3048)
			(end 0.67945 0.3048)
			(stroke
				(width 0.1)
				(type default)
			)
			(layer "B.Fab")
		)
		(fp_line
			(start -0.120396 0.3048)
			(end -0.120396 0.2794)
			(stroke
				(width 0.1)
				(type default)
			)
			(layer "B.Fab")
		)
		(fp_line
			(start -0.67945 0.3048)
			(end -0.120396 0.3048)
			(stroke
				(width 0.1)
				(type default)
			)
			(layer "B.Fab")
		)
		(pad "1" smd circle
			(at 0.40005 0 270)
			(size 0 0)
			(layers "B.Cu" "B.Mask" "B.Paste")
			(net "P1V8_CPU1_RT2_1A")
		)
		(pad "2" smd circle
			(at -0.40005 0 270)
			(size 0 0)
			(layers "B.Cu" "B.Mask" "B.Paste")
			(net "GND")
		)
	)
	(footprint ""
		(layer "B.Cu")
		(at 409.146248 -396.393162 -90)
		(property "Reference" "C782"
			(at 0 0 90)
			(layer "B.SilkS")
			(hide yes)
			(effects
				(font
					(size 1.27 1.27)
				)
				(justify mirror)
			)
		)
		(property "Value" ""
			(at 0 0 90)
			(layer "B.Fab")
			(effects
				(font
					(size 1.27 1.27)
				)
				(justify mirror)
			)
		)
		(duplicate_pad_numbers_are_jumpers no)
		(fp_line
			(start -0.299974 0.150114)
			(end 0.299974 0.150114)
			(stroke
				(width 0.1)
				(type default)
			)
			(layer "B.Fab")
		)
		(fp_line
			(start 0.299974 0.150114)
			(end 0.299974 -0.150114)
			(stroke
				(width 0.1)
				(type default)
			)
			(layer "B.Fab")
		)
		(fp_line
			(start -0.299974 -0.150114)
			(end -0.299974 0.150114)
			(stroke
				(width 0.1)
				(type default)
			)
			(layer "B.Fab")
		)
		(fp_line
			(start 0.299974 -0.150114)
			(end -0.299974 -0.150114)
			(stroke
				(width 0.1)
				(type default)
			)
			(layer "B.Fab")
		)
		(pad "1" smd rect
			(at 0.2667 0 90)
			(size 0.3048 0.381)
			(layers "B.Cu" "B.Mask" "B.Paste")
			(net "P0V9_CPU0_RT_2D")
		)
		(pad "2" smd rect
			(at -0.2667 0 90)
			(size 0.3048 0.381)
			(layers "B.Cu" "B.Mask" "B.Paste")
			(net "GND")
		)
	)
	(footprint ""
		(layer "B.Cu")
		(at 164.902388 -13.65504 90)
		(property "Reference" "R2423"
			(at 0 0 90)
			(layer "B.SilkS")
			(hide yes)
			(effects
				(font
					(size 1.27 1.27)
				)
				(justify mirror)
			)
		)
		(property "Value" ""
			(at 0 0 90)
			(layer "B.Fab")
			(effects
				(font
					(size 1.27 1.27)
				)
				(justify mirror)
			)
		)
		(duplicate_pad_numbers_are_jumpers no)
		(fp_line
			(start 0.7874 -0.4064)
			(end -0.7874 -0.4064)
			(stroke
				(width 0.1524)
				(type default)
			)
			(layer "B.SilkS")
		)
		(fp_line
			(start -0.7874 -0.4064)
			(end -0.7874 0.4064)
			(stroke
				(width 0.1524)
				(type default)
			)
			(layer "B.SilkS")
		)
		(fp_line
			(start 0.7874 0.4064)
			(end 0.7874 -0.4064)
			(stroke
				(width 0.1524)
				(type default)
			)
			(layer "B.SilkS")
		)
		(fp_line
			(start -0.7874 0.4064)
			(end 0.7874 0.4064)
			(stroke
				(width 0.1524)
				(type default)
			)
			(layer "B.SilkS")
		)
		(fp_line
			(start 0.67945 -0.305054)
			(end 0.12065 -0.305054)
			(stroke
				(width 0.1)
				(type default)
			)
			(layer "B.Fab")
		)
		(fp_line
			(start 0.12065 -0.305054)
			(end 0.12065 -0.2794)
			(stroke
				(width 0.1)
				(type default)
			)
			(layer "B.Fab")
		)
		(fp_line
			(start -0.12065 -0.3048)
			(end -0.67945 -0.3048)
			(stroke
				(width 0.1)
				(type default)
			)
			(layer "B.Fab")
		)
		(fp_line
			(start -0.67945 -0.3048)
			(end -0.67945 0.3048)
			(stroke
				(width 0.1)
				(type default)
			)
			(layer "B.Fab")
		)
		(fp_line
			(start 0.12065 -0.2794)
			(end -0.12065 -0.2794)
			(stroke
				(width 0.1)
				(type default)
			)
			(layer "B.Fab")
		)
		(fp_line
			(start -0.12065 -0.2794)
			(end -0.12065 -0.3048)
			(stroke
				(width 0.1)
				(type default)
			)
			(layer "B.Fab")
		)
		(fp_line
			(start 0.12065 0.2794)
			(end 0.12065 0.3048)
			(stroke
				(width 0.1)
				(type default)
			)
			(layer "B.Fab")
		)
		(fp_line
			(start -0.120396 0.2794)
			(end 0.12065 0.2794)
			(stroke
				(width 0.1)
				(type default)
			)
			(layer "B.Fab")
		)
		(fp_line
			(start 0.67945 0.3048)
			(end 0.67945 -0.305054)
			(stroke
				(width 0.1)
				(type default)
			)
			(layer "B.Fab")
		)
		(fp_line
			(start 0.12065 0.3048)
			(end 0.67945 0.3048)
			(stroke
				(width 0.1)
				(type default)
			)
			(layer "B.Fab")
		)
		(fp_line
			(start -0.120396 0.3048)
			(end -0.120396 0.2794)
			(stroke
				(width 0.1)
				(type default)
			)
			(layer "B.Fab")
		)
		(fp_line
			(start -0.67945 0.3048)
			(end -0.120396 0.3048)
			(stroke
				(width 0.1)
				(type default)
			)
			(layer "B.Fab")
		)
		(pad "1" smd circle
			(at 0.40005 0 270)
			(size 0 0)
			(layers "B.Cu" "B.Mask" "B.Paste")
			(net "SMB_PMBUS_3V3AUX_SCL")
		)
		(pad "2" smd circle
			(at -0.40005 0 270)
			(size 0 0)
			(layers "B.Cu" "B.Mask" "B.Paste")
			(net "SMB_PMBUS_3V3AUX_SCL_R0")
		)
	)
)
